(kicad_pcb
	(version 20260206)
	(generator "pcbnew")
	(generator_version "10.0")
	(general
		(thickness 1.6)
		(legacy_teardrops no)
	)
	(paper "A4")
	(title_block
		(title "01162023_DA0F0TEBIF0_F0T_Expander_BD_F_brd_V02_OCP.brd")
		(comment 1 "Grand Teton / footprints 3344-3350 of 9728")
	)
	(layers
		(0 "F.Cu" signal "TOP")
		(4 "In1.Cu" signal "GND")
		(6 "In2.Cu" signal "VCC")
		(8 "In3.Cu" signal "VCC1")
		(10 "In4.Cu" signal "GND1")
		(12 "In5.Cu" signal "IN1")
		(14 "In6.Cu" signal "GND2")
		(16 "In7.Cu" signal "IN2")
		(18 "In8.Cu" signal "GND3")
		(20 "In9.Cu" signal "IN3")
		(22 "In10.Cu" signal "GND4")
		(24 "In11.Cu" signal "IN4")
		(26 "In12.Cu" signal "GND5")
		(28 "In13.Cu" signal "IN5")
		(30 "In14.Cu" signal "GND6")
		(32 "In15.Cu" signal "IN6")
		(34 "In16.Cu" signal "GND7")
		(2 "B.Cu" signal "BOTTOM")
		(9 "F.Adhes" user "F.Adhesive")
		(11 "B.Adhes" user "B.Adhesive")
		(13 "F.Paste" user "Package Geometry/Pastemask Top")
		(15 "B.Paste" user "Package Geometry/Pastemask Bottom")
		(5 "F.SilkS" user "Ref Des/Silkscreen Top")
		(7 "B.SilkS" user "Ref Des/Silkscreen Bottom")
		(1 "F.Mask" user "Board Geometry/Soldermask Top")
		(3 "B.Mask" user "Board Geometry/Soldermask Bottom")
		(17 "Dwgs.User" user "User.Drawings")
		(19 "Cmts.User" user "User.Comments")
		(21 "Eco1.User" user "User.Eco1")
		(23 "Eco2.User" user "User.Eco2")
		(25 "Edge.Cuts" user "Board Geometry/Outline")
		(27 "Margin" user)
		(31 "F.CrtYd" user "Package Geometry/Place Bound Top")
		(29 "B.CrtYd" user "Package Geometry/Place Bound Bottom")
		(35 "F.Fab" user "Ref Des/Assembly Top")
		(33 "B.Fab" user "Ref Des/Assembly Bottom")
	)
	(footprint ""
		(layer "F.Cu")
		(at 336.443574 -45.88891)
		(property "Reference" "R631"
			(at 0 0 0)
			(layer "F.SilkS")
			(hide yes)
			(effects
				(font
					(size 1.27 1.27)
				)
			)
		)
		(property "Value" ""
			(at 0 0 0)
			(layer "F.Fab")
			(effects
				(font
					(size 1.27 1.27)
				)
			)
		)
		(duplicate_pad_numbers_are_jumpers no)
		(fp_line
			(start -0.7874 -0.4064)
			(end 0.7874 -0.4064)
			(stroke
				(width 0.1524)
				(type default)
			)
			(layer "F.SilkS")
		)
		(fp_line
			(start -0.7874 0.4064)
			(end -0.7874 -0.4064)
			(stroke
				(width 0.1524)
				(type default)
			)
			(layer "F.SilkS")
		)
		(fp_line
			(start 0.7874 -0.4064)
			(end 0.7874 0.4064)
			(stroke
				(width 0.1524)
				(type default)
			)
			(layer "F.SilkS")
		)
		(fp_line
			(start 0.7874 0.4064)
			(end -0.7874 0.4064)
			(stroke
				(width 0.1524)
				(type default)
			)
			(layer "F.SilkS")
		)
		(fp_line
			(start -0.67945 -0.305054)
			(end -0.12065 -0.305054)
			(stroke
				(width 0.1)
				(type default)
			)
			(layer "F.Fab")
		)
		(fp_line
			(start -0.67945 0.3048)
			(end -0.67945 -0.305054)
			(stroke
				(width 0.1)
				(type default)
			)
			(layer "F.Fab")
		)
		(fp_line
			(start -0.12065 -0.305054)
			(end -0.12065 -0.2794)
			(stroke
				(width 0.1)
				(type default)
			)
			(layer "F.Fab")
		)
		(fp_line
			(start -0.12065 -0.2794)
			(end 0.12065 -0.2794)
			(stroke
				(width 0.1)
				(type default)
			)
			(layer "F.Fab")
		)
		(fp_line
			(start -0.12065 0.2794)
			(end -0.12065 0.3048)
			(stroke
				(width 0.1)
				(type default)
			)
			(layer "F.Fab")
		)
		(fp_line
			(start -0.12065 0.3048)
			(end -0.67945 0.3048)
			(stroke
				(width 0.1)
				(type default)
			)
			(layer "F.Fab")
		)
		(fp_line
			(start 0.120396 0.2794)
			(end -0.12065 0.2794)
			(stroke
				(width 0.1)
				(type default)
			)
			(layer "F.Fab")
		)
		(fp_line
			(start 0.120396 0.3048)
			(end 0.120396 0.2794)
			(stroke
				(width 0.1)
				(type default)
			)
			(layer "F.Fab")
		)
		(fp_line
			(start 0.12065 -0.3048)
			(end 0.67945 -0.3048)
			(stroke
				(width 0.1)
				(type default)
			)
			(layer "F.Fab")
		)
		(fp_line
			(start 0.12065 -0.2794)
			(end 0.12065 -0.3048)
			(stroke
				(width 0.1)
				(type default)
			)
			(layer "F.Fab")
		)
		(fp_line
			(start 0.67945 -0.3048)
			(end 0.67945 0.3048)
			(stroke
				(width 0.1)
				(type default)
			)
			(layer "F.Fab")
		)
		(fp_line
			(start 0.67945 0.3048)
			(end 0.120396 0.3048)
			(stroke
				(width 0.1)
				(type default)
			)
			(layer "F.Fab")
		)
		(pad "1" smd circle
			(at -0.40005 0)
			(size 0 0)
			(layers "F.Cu" "F.Mask" "F.Paste")
			(net "SSD11_ADC_A0")
		)
		(pad "2" smd circle
			(at 0.40005 0)
			(size 0 0)
			(layers "F.Cu" "F.Mask" "F.Paste")
			(net "GND")
		)
	)
	(footprint ""
		(layer "F.Cu")
		(at 224.851976 -368.010186 180)
		(property "Reference" "PR42"
			(at 0 0 180)
			(layer "F.SilkS")
			(hide yes)
			(effects
				(font
					(size 1.27 1.27)
				)
			)
		)
		(property "Value" ""
			(at 0 0 180)
			(layer "F.Fab")
			(effects
				(font
					(size 1.27 1.27)
				)
			)
		)
		(duplicate_pad_numbers_are_jumpers no)
		(fp_line
			(start 0.7874 0.4064)
			(end -0.7874 0.4064)
			(stroke
				(width 0.1524)
				(type default)
			)
			(layer "F.SilkS")
		)
		(fp_line
			(start 0.7874 -0.4064)
			(end 0.7874 0.4064)
			(stroke
				(width 0.1524)
				(type default)
			)
			(layer "F.SilkS")
		)
		(fp_line
			(start -0.7874 0.4064)
			(end -0.7874 -0.4064)
			(stroke
				(width 0.1524)
				(type default)
			)
			(layer "F.SilkS")
		)
		(fp_line
			(start -0.7874 -0.4064)
			(end 0.7874 -0.4064)
			(stroke
				(width 0.1524)
				(type default)
			)
			(layer "F.SilkS")
		)
		(fp_line
			(start 0.67945 0.3048)
			(end 0.120396 0.3048)
			(stroke
				(width 0.1)
				(type default)
			)
			(layer "F.Fab")
		)
		(fp_line
			(start 0.67945 -0.3048)
			(end 0.67945 0.3048)
			(stroke
				(width 0.1)
				(type default)
			)
			(layer "F.Fab")
		)
		(fp_line
			(start 0.12065 -0.2794)
			(end 0.12065 -0.3048)
			(stroke
				(width 0.1)
				(type default)
			)
			(layer "F.Fab")
		)
		(fp_line
			(start 0.12065 -0.3048)
			(end 0.67945 -0.3048)
			(stroke
				(width 0.1)
				(type default)
			)
			(layer "F.Fab")
		)
		(fp_line
			(start 0.120396 0.3048)
			(end 0.120396 0.2794)
			(stroke
				(width 0.1)
				(type default)
			)
			(layer "F.Fab")
		)
		(fp_line
			(start 0.120396 0.2794)
			(end -0.12065 0.2794)
			(stroke
				(width 0.1)
				(type default)
			)
			(layer "F.Fab")
		)
		(fp_line
			(start -0.12065 0.3048)
			(end -0.67945 0.3048)
			(stroke
				(width 0.1)
				(type default)
			)
			(layer "F.Fab")
		)
		(fp_line
			(start -0.12065 0.2794)
			(end -0.12065 0.3048)
			(stroke
				(width 0.1)
				(type default)
			)
			(layer "F.Fab")
		)
		(fp_line
			(start -0.12065 -0.2794)
			(end 0.12065 -0.2794)
			(stroke
				(width 0.1)
				(type default)
			)
			(layer "F.Fab")
		)
		(fp_line
			(start -0.12065 -0.305054)
			(end -0.12065 -0.2794)
			(stroke
				(width 0.1)
				(type default)
			)
			(layer "F.Fab")
		)
		(fp_line
			(start -0.67945 0.3048)
			(end -0.67945 -0.305054)
			(stroke
				(width 0.1)
				(type default)
			)
			(layer "F.Fab")
		)
		(fp_line
			(start -0.67945 -0.305054)
			(end -0.12065 -0.305054)
			(stroke
				(width 0.1)
				(type default)
			)
			(layer "F.Fab")
		)
		(pad "1" smd circle
			(at -0.40005 0 180)
			(size 0 0)
			(layers "F.Cu" "F.Mask" "F.Paste")
			(net "HSC_CS_2")
		)
		(pad "2" smd circle
			(at 0.40005 0 180)
			(size 0 0)
			(layers "F.Cu" "F.Mask" "F.Paste")
			(net "AGND_HSC")
		)
	)
	(footprint ""
		(layer "F.Cu")
		(at 376.706384 -252.356874 -90)
		(property "Reference" "R1423"
			(at 0 0 270)
			(layer "F.SilkS")
			(hide yes)
			(effects
				(font
					(size 1.27 1.27)
				)
			)
		)
		(property "Value" ""
			(at 0 0 270)
			(layer "F.Fab")
			(effects
				(font
					(size 1.27 1.27)
				)
			)
		)
		(duplicate_pad_numbers_are_jumpers no)
		(fp_line
			(start -0.7874 0.4064)
			(end -0.7874 -0.4064)
			(stroke
				(width 0.1524)
				(type default)
			)
			(layer "F.SilkS")
		)
		(fp_line
			(start 0.7874 0.4064)
			(end -0.7874 0.4064)
			(stroke
				(width 0.1524)
				(type default)
			)
			(layer "F.SilkS")
		)
		(fp_line
			(start -0.7874 -0.4064)
			(end 0.7874 -0.4064)
			(stroke
				(width 0.1524)
				(type default)
			)
			(layer "F.SilkS")
		)
		(fp_line
			(start 0.7874 -0.4064)
			(end 0.7874 0.4064)
			(stroke
				(width 0.1524)
				(type default)
			)
			(layer "F.SilkS")
		)
		(fp_line
			(start -0.67945 0.3048)
			(end -0.67945 -0.305054)
			(stroke
				(width 0.1)
				(type default)
			)
			(layer "F.Fab")
		)
		(fp_line
			(start -0.12065 0.3048)
			(end -0.67945 0.3048)
			(stroke
				(width 0.1)
				(type default)
			)
			(layer "F.Fab")
		)
		(fp_line
			(start 0.120396 0.3048)
			(end 0.120396 0.2794)
			(stroke
				(width 0.1)
				(type default)
			)
			(layer "F.Fab")
		)
		(fp_line
			(start 0.67945 0.3048)
			(end 0.120396 0.3048)
			(stroke
				(width 0.1)
				(type default)
			)
			(layer "F.Fab")
		)
		(fp_line
			(start -0.12065 0.2794)
			(end -0.12065 0.3048)
			(stroke
				(width 0.1)
				(type default)
			)
			(layer "F.Fab")
		)
		(fp_line
			(start 0.120396 0.2794)
			(end -0.12065 0.2794)
			(stroke
				(width 0.1)
				(type default)
			)
			(layer "F.Fab")
		)
		(fp_line
			(start -0.12065 -0.2794)
			(end 0.12065 -0.2794)
			(stroke
				(width 0.1)
				(type default)
			)
			(layer "F.Fab")
		)
		(fp_line
			(start 0.12065 -0.2794)
			(end 0.12065 -0.3048)
			(stroke
				(width 0.1)
				(type default)
			)
			(layer "F.Fab")
		)
		(fp_line
			(start 0.12065 -0.3048)
			(end 0.67945 -0.3048)
			(stroke
				(width 0.1)
				(type default)
			)
			(layer "F.Fab")
		)
		(fp_line
			(start 0.67945 -0.3048)
			(end 0.67945 0.3048)
			(stroke
				(width 0.1)
				(type default)
			)
			(layer "F.Fab")
		)
		(fp_line
			(start -0.67945 -0.305054)
			(end -0.12065 -0.305054)
			(stroke
				(width 0.1)
				(type default)
			)
			(layer "F.Fab")
		)
		(fp_line
			(start -0.12065 -0.305054)
			(end -0.12065 -0.2794)
			(stroke
				(width 0.1)
				(type default)
			)
			(layer "F.Fab")
		)
		(pad "1" smd circle
			(at -0.40005 0 270)
			(size 0 0)
			(layers "F.Cu" "F.Mask" "F.Paste")
			(net "GND")
		)
		(pad "2" smd circle
			(at 0.40005 0 270)
			(size 0 0)
			(layers "F.Cu" "F.Mask" "F.Paste")
			(net "PEX3_DBG_MODE3")
		)
	)
	(footprint ""
		(layer "F.Cu")
		(at 379.147832 -40.037258 90)
		(property "Reference" "U374"
			(at 0.196342 2.310638 90)
			(unlocked yes)
			(layer "F.SilkS")
			(effects
				(font
					(size 0.7874 0.5842)
					(thickness 0.1524)
				)
			)
		)
		(property "Value" ""
			(at 0 0 90)
			(layer "F.Fab")
			(effects
				(font
					(size 1.27 1.27)
				)
			)
		)
		(duplicate_pad_numbers_are_jumpers no)
		(fp_line
			(start -1.949958 -1.610106)
			(end 1.949958 -1.610106)
			(stroke
				(width 0.1524)
				(type default)
			)
			(layer "F.SilkS")
		)
		(fp_line
			(start 1.949958 -1.560068)
			(end 1.949958 1.610106)
			(stroke
				(width 0.1524)
				(type default)
			)
			(layer "F.SilkS")
		)
		(fp_line
			(start 1.949958 1.610106)
			(end -1.949958 1.610106)
			(stroke
				(width 0.1524)
				(type default)
			)
			(layer "F.SilkS")
		)
		(fp_line
			(start -1.949958 1.610106)
			(end -1.949958 -1.610106)
			(stroke
				(width 0.1524)
				(type default)
			)
			(layer "F.SilkS")
		)
		(fp_line
			(start 0.750062 -1.560068)
			(end 0.750062 1.560068)
			(stroke
				(width 0.1)
				(type default)
			)
			(layer "F.Fab")
		)
		(fp_line
			(start -0.750062 -1.560068)
			(end 0.750062 -1.560068)
			(stroke
				(width 0.1)
				(type default)
			)
			(layer "F.Fab")
		)
		(fp_line
			(start 0.750062 1.560068)
			(end -0.750062 1.560068)
			(stroke
				(width 0.1)
				(type default)
			)
			(layer "F.Fab")
		)
		(fp_line
			(start -0.750062 1.560068)
			(end -0.750062 -1.560068)
			(stroke
				(width 0.1)
				(type default)
			)
			(layer "F.Fab")
		)
		(pad "D" smd rect
			(at 1.100074 0)
			(size 1.016 1.4224)
			(layers "F.Cu" "F.Mask" "F.Paste")
			(net "SSD13_AUX_P3V3_EN")
		)
		(pad "G" smd rect
			(at -1.100074 -0.94996)
			(size 1.016 1.4224)
			(layers "F.Cu" "F.Mask" "F.Paste")
			(net "PRSNT_SSD13_R1_N")
		)
		(pad "S" smd rect
			(at -1.100074 0.94996)
			(size 1.016 1.4224)
			(layers "F.Cu" "F.Mask" "F.Paste")
			(net "GND")
		)
	)
	(footprint ""
		(layer "F.Cu")
		(at 332.045564 -356.244906 90)
		(property "Reference" "C570"
			(at 0 0 90)
			(layer "F.SilkS")
			(hide yes)
			(effects
				(font
					(size 1.27 1.27)
				)
			)
		)
		(property "Value" ""
			(at 0 0 90)
			(layer "F.Fab")
			(effects
				(font
					(size 1.27 1.27)
				)
			)
		)
		(duplicate_pad_numbers_are_jumpers no)
		(fp_line
			(start 0.299974 -0.150114)
			(end 0.299974 0.150114)
			(stroke
				(width 0.1)
				(type default)
			)
			(layer "F.Fab")
		)
		(fp_line
			(start -0.299974 -0.150114)
			(end 0.299974 -0.150114)
			(stroke
				(width 0.1)
				(type default)
			)
			(layer "F.Fab")
		)
		(fp_line
			(start 0.299974 0.150114)
			(end -0.299974 0.150114)
			(stroke
				(width 0.1)
				(type default)
			)
			(layer "F.Fab")
		)
		(fp_line
			(start -0.299974 0.150114)
			(end -0.299974 -0.150114)
			(stroke
				(width 0.1)
				(type default)
			)
			(layer "F.Fab")
		)
		(pad "1" smd rect
			(at -0.2667 0 90)
			(size 0.3048 0.381)
			(layers "F.Cu" "F.Mask" "F.Paste")
			(net "P5E_PEX2_STN6_TX_DN<102>")
		)
		(pad "2" smd rect
			(at 0.2667 0 90)
			(size 0.3048 0.381)
			(layers "F.Cu" "F.Mask" "F.Paste")
			(net "P5E_PEX2_STN6_TX_C_DN<102>")
		)
	)
	(footprint ""
		(layer "F.Cu")
		(at 404.439628 -367.407952)
		(property "Reference" "R6678"
			(at 0 0 0)
			(layer "F.SilkS")
			(hide yes)
			(effects
				(font
					(size 1.27 1.27)
				)
			)
		)
		(property "Value" ""
			(at 0 0 0)
			(layer "F.Fab")
			(effects
				(font
					(size 1.27 1.27)
				)
			)
		)
		(duplicate_pad_numbers_are_jumpers no)
		(fp_line
			(start -0.7874 -0.4064)
			(end 0.7874 -0.4064)
			(stroke
				(width 0.1524)
				(type default)
			)
			(layer "F.SilkS")
		)
		(fp_line
			(start -0.7874 0.4064)
			(end -0.7874 -0.4064)
			(stroke
				(width 0.1524)
				(type default)
			)
			(layer "F.SilkS")
		)
		(fp_line
			(start 0.7874 -0.4064)
			(end 0.7874 0.4064)
			(stroke
				(width 0.1524)
				(type default)
			)
			(layer "F.SilkS")
		)
		(fp_line
			(start 0.7874 0.4064)
			(end -0.7874 0.4064)
			(stroke
				(width 0.1524)
				(type default)
			)
			(layer "F.SilkS")
		)
		(fp_line
			(start -0.67945 -0.305054)
			(end -0.12065 -0.305054)
			(stroke
				(width 0.1)
				(type default)
			)
			(layer "F.Fab")
		)
		(fp_line
			(start -0.67945 0.3048)
			(end -0.67945 -0.305054)
			(stroke
				(width 0.1)
				(type default)
			)
			(layer "F.Fab")
		)
		(fp_line
			(start -0.12065 -0.305054)
			(end -0.12065 -0.2794)
			(stroke
				(width 0.1)
				(type default)
			)
			(layer "F.Fab")
		)
		(fp_line
			(start -0.12065 -0.2794)
			(end 0.12065 -0.2794)
			(stroke
				(width 0.1)
				(type default)
			)
			(layer "F.Fab")
		)
		(fp_line
			(start -0.12065 0.2794)
			(end -0.12065 0.3048)
			(stroke
				(width 0.1)
				(type default)
			)
			(layer "F.Fab")
		)
		(fp_line
			(start -0.12065 0.3048)
			(end -0.67945 0.3048)
			(stroke
				(width 0.1)
				(type default)
			)
			(layer "F.Fab")
		)
		(fp_line
			(start 0.120396 0.2794)
			(end -0.12065 0.2794)
			(stroke
				(width 0.1)
				(type default)
			)
			(layer "F.Fab")
		)
		(fp_line
			(start 0.120396 0.3048)
			(end 0.120396 0.2794)
			(stroke
				(width 0.1)
				(type default)
			)
			(layer "F.Fab")
		)
		(fp_line
			(start 0.12065 -0.3048)
			(end 0.67945 -0.3048)
			(stroke
				(width 0.1)
				(type default)
			)
			(layer "F.Fab")
		)
		(fp_line
			(start 0.12065 -0.2794)
			(end 0.12065 -0.3048)
			(stroke
				(width 0.1)
				(type default)
			)
			(layer "F.Fab")
		)
		(fp_line
			(start 0.67945 -0.3048)
			(end 0.67945 0.3048)
			(stroke
				(width 0.1)
				(type default)
			)
			(layer "F.Fab")
		)
		(fp_line
			(start 0.67945 0.3048)
			(end 0.120396 0.3048)
			(stroke
				(width 0.1)
				(type default)
			)
			(layer "F.Fab")
		)
		(pad "1" smd circle
			(at -0.40005 0)
			(size 0 0)
			(layers "F.Cu" "F.Mask" "F.Paste")
			(net "GPU_3V3IO_RSVD1_ISO")
		)
		(pad "2" smd circle
			(at 0.40005 0)
			(size 0 0)
			(layers "F.Cu" "F.Mask" "F.Paste")
			(net "P3V3_AUX")
		)
	)
	(footprint ""
		(layer "F.Cu")
		(at 150.319486 -390.398254 -90)
		(property "Reference" "R1839"
			(at 0 0 270)
			(layer "F.SilkS")
			(hide yes)
			(effects
				(font
					(size 1.27 1.27)
				)
			)
		)
		(property "Value" ""
			(at 0 0 270)
			(layer "F.Fab")
			(effects
				(font
					(size 1.27 1.27)
				)
			)
		)
		(duplicate_pad_numbers_are_jumpers no)
		(fp_line
			(start -0.7874 0.4064)
			(end -0.7874 -0.4064)
			(stroke
				(width 0.1524)
				(type default)
			)
			(layer "F.SilkS")
		)
		(fp_line
			(start 0.7874 0.4064)
			(end -0.7874 0.4064)
			(stroke
				(width 0.1524)
				(type default)
			)
			(layer "F.SilkS")
		)
		(fp_line
			(start -0.7874 -0.4064)
			(end 0.7874 -0.4064)
			(stroke
				(width 0.1524)
				(type default)
			)
			(layer "F.SilkS")
		)
		(fp_line
			(start 0.7874 -0.4064)
			(end 0.7874 0.4064)
			(stroke
				(width 0.1524)
				(type default)
			)
			(layer "F.SilkS")
		)
		(fp_line
			(start -0.67945 0.3048)
			(end -0.67945 -0.305054)
			(stroke
				(width 0.1)
				(type default)
			)
			(layer "F.Fab")
		)
		(fp_line
			(start -0.12065 0.3048)
			(end -0.67945 0.3048)
			(stroke
				(width 0.1)
				(type default)
			)
			(layer "F.Fab")
		)
		(fp_line
			(start 0.120396 0.3048)
			(end 0.120396 0.2794)
			(stroke
				(width 0.1)
				(type default)
			)
			(layer "F.Fab")
		)
		(fp_line
			(start 0.67945 0.3048)
			(end 0.120396 0.3048)
			(stroke
				(width 0.1)
				(type default)
			)
			(layer "F.Fab")
		)
		(fp_line
			(start -0.12065 0.2794)
			(end -0.12065 0.3048)
			(stroke
				(width 0.1)
				(type default)
			)
			(layer "F.Fab")
		)
		(fp_line
			(start 0.120396 0.2794)
			(end -0.12065 0.2794)
			(stroke
				(width 0.1)
				(type default)
			)
			(layer "F.Fab")
		)
		(fp_line
			(start -0.12065 -0.2794)
			(end 0.12065 -0.2794)
			(stroke
				(width 0.1)
				(type default)
			)
			(layer "F.Fab")
		)
		(fp_line
			(start 0.12065 -0.2794)
			(end 0.12065 -0.3048)
			(stroke
				(width 0.1)
				(type default)
			)
			(layer "F.Fab")
		)
		(fp_line
			(start 0.12065 -0.3048)
			(end 0.67945 -0.3048)
			(stroke
				(width 0.1)
				(type default)
			)
			(layer "F.Fab")
		)
		(fp_line
			(start 0.67945 -0.3048)
			(end 0.67945 0.3048)
			(stroke
				(width 0.1)
				(type default)
			)
			(layer "F.Fab")
		)
		(fp_line
			(start -0.67945 -0.305054)
			(end -0.12065 -0.305054)
			(stroke
				(width 0.1)
				(type default)
			)
			(layer "F.Fab")
		)
		(fp_line
			(start -0.12065 -0.305054)
			(end -0.12065 -0.2794)
			(stroke
				(width 0.1)
				(type default)
			)
			(layer "F.Fab")
		)
		(pad "1" smd circle
			(at -0.40005 0 270)
			(size 0 0)
			(layers "F.Cu" "F.Mask" "F.Paste")
			(net "PRSNT_GPU_HMC_R_N")
		)
		(pad "2" smd circle
			(at 0.40005 0 270)
			(size 0 0)
			(layers "F.Cu" "F.Mask" "F.Paste")
			(net "PRSNT_GPU_HMC_N")
		)
	)
)
